(kicad_pcb
	(version 20241229)
	(generator "pcbnew")
	(generator_version "9.0")
	(general
		(thickness 1.62)
		(legacy_teardrops no)
	)
	(paper "A3")
	(title_block
		(title "COM Express 7 Baseboard")
		(date "2025-02-04")
		(rev "1.1.2")
		(company "Antmicro Ltd")
		(comment 1 "www.antmicro.com")
		(comment 9 "footprints 795-799 of 802")
	)
	(layers
		(0 "F.Cu" signal)
		(4 "In1.Cu" signal)
		(6 "In2.Cu" signal)
		(8 "In3.Cu" signal)
		(10 "In4.Cu" signal)
		(12 "In5.Cu" signal)
		(14 "In6.Cu" signal)
		(2 "B.Cu" signal)
		(9 "F.Adhes" user "F.Adhesive")
		(11 "B.Adhes" user "B.Adhesive")
		(13 "F.Paste" user)
		(15 "B.Paste" user)
		(5 "F.SilkS" user "F.Silkscreen")
		(7 "B.SilkS" user "B.Silkscreen")
		(1 "F.Mask" user)
		(3 "B.Mask" user)
		(17 "Dwgs.User" user "User.Drawings")
		(19 "Cmts.User" user "User.Comments")
		(21 "Eco1.User" user "User.Eco1")
		(23 "Eco2.User" user "User.Eco2")
		(25 "Edge.Cuts" user)
		(27 "Margin" user)
		(31 "F.CrtYd" user "F.Courtyard")
		(29 "B.CrtYd" user "B.Courtyard")
		(35 "F.Fab" user)
		(33 "B.Fab" user)
	)
	(footprint "antmicro-footprints:TP_SMD_0.75mm"
		(layer "B.Cu")
		(at 213.33 124.85 -90)
		(property "Reference" "TP45"
			(at -3.09 -0.47 90)
			(layer "B.SilkS")
			(effects
				(font
					(size 0.7 0.7)
					(thickness 0.15)
				)
				(justify left bottom mirror)
			)
		)
		(property "Value" "TP_0.75mm_SMD"
			(at 0 -1.2 90)
			(layer "B.Fab")
			(effects
				(font
					(size 0.7 0.7)
					(thickness 0.15)
				)
				(justify left bottom mirror)
			)
		)
		(property "Author" "Antmicro"
			(at 88.48 338.18 0)
			(layer "B.Fab")
			(hide yes)
			(effects
				(font
					(size 1 1)
					(thickness 0.15)
				)
				(justify mirror)
			)
		)
		(property "License" "Apache-2.0"
			(at 88.48 338.18 0)
			(layer "B.Fab")
			(hide yes)
			(effects
				(font
					(size 1 1)
					(thickness 0.15)
				)
				(justify mirror)
			)
		)
		(property "MPN" ""
			(at 88.48 338.18 0)
			(layer "B.Fab")
			(hide yes)
			(effects
				(font
					(size 1 1)
					(thickness 0.15)
				)
				(justify mirror)
			)
		)
		(property "Manufacturer" ""
			(at 88.48 338.18 0)
			(layer "B.Fab")
			(hide yes)
			(effects
				(font
					(size 1 1)
					(thickness 0.15)
				)
				(justify mirror)
			)
		)
		(property "Public" "False"
			(at 88.48 338.18 0)
			(layer "B.Fab")
			(hide yes)
			(effects
				(font
					(size 1 1)
					(thickness 0.15)
				)
				(justify mirror)
			)
		)
		(sheetname "PCIe misc")
		(sheetfile "pcie_misc.kicad_sch")
		(attr exclude_from_pos_files exclude_from_bom)
		(fp_circle
			(center 0 0)
			(end 0.475 0)
			(stroke
				(width 0.05)
				(type default)
			)
			(fill no)
			(layer "B.CrtYd")
		)
		(pad "1" smd circle
			(at 0 0 270)
			(size 0.75 0.75)
			(layers "B.Cu" "B.Mask")
			(net 710 "Net-(U37-SDAT)")
			(pinfunction "1")
			(pintype "passive")
			(teardrops
				(best_length_ratio 0.4)
				(max_length 1)
				(best_width_ratio 0.9)
				(max_width 2)
				(curved_edges yes)
				(filter_ratio 0.9)
				(enabled yes)
				(allow_two_segments yes)
				(prefer_zone_connections yes)
			)
		)
	)
	(footprint "antmicro-footprints:C_0402_1005Metric"
		(layer "B.Cu")
		(at 130.29 142.36 90)
		(descr "Capacitor SMD 0402")
		(tags "capacitor SMD 0402")
		(property "Reference" "C189"
			(at -1.4 -0.49 90)
			(layer "B.SilkS")
			(effects
				(font
					(size 0.7 0.7)
					(thickness 0.15)
				)
				(justify right bottom mirror)
			)
		)
		(property "Value" "C_100n_0402"
			(at -1.022927 -2.155213 90)
			(layer "B.Fab")
			(effects
				(font
					(size 0.7 0.7)
					(thickness 0.15)
				)
				(justify right bottom mirror)
			)
		)
		(property "Datasheet" "https://www.murata.com/products/productdetail?partno=GRM155R61H104KE14%23"
			(at 0 0 90)
			(layer "F.Fab")
			(hide yes)
			(effects
				(font
					(size 1.27 1.27)
					(thickness 0.15)
				)
			)
		)
		(property "Author" "Antmicro"
			(at 272.65 12.07 0)
			(layer "B.Fab")
			(hide yes)
			(effects
				(font
					(size 1 1)
					(thickness 0.15)
				)
				(justify mirror)
			)
		)
		(property "Dielectric" "X5R"
			(at 272.65 12.07 0)
			(layer "B.Fab")
			(hide yes)
			(effects
				(font
					(size 1 1)
					(thickness 0.15)
				)
				(justify mirror)
			)
		)
		(property "License" "Apache-2.0"
			(at 272.65 12.07 0)
			(layer "B.Fab")
			(hide yes)
			(effects
				(font
					(size 1 1)
					(thickness 0.15)
				)
				(justify mirror)
			)
		)
		(property "MPN" "GRM155R61H104KE14D"
			(at 272.65 12.07 0)
			(layer "B.Fab")
			(hide yes)
			(effects
				(font
					(size 1 1)
					(thickness 0.15)
				)
				(justify mirror)
			)
		)
		(property "Manufacturer" "Murata"
			(at 272.65 12.07 0)
			(layer "B.Fab")
			(hide yes)
			(effects
				(font
					(size 1 1)
					(thickness 0.15)
				)
				(justify mirror)
			)
		)
		(property "Public" "False"
			(at 272.65 12.07 0)
			(layer "B.Fab")
			(hide yes)
			(effects
				(font
					(size 1 1)
					(thickness 0.15)
				)
				(justify mirror)
			)
		)
		(property "Val" "100n"
			(at 272.65 12.07 0)
			(layer "B.Fab")
			(hide yes)
			(effects
				(font
					(size 1 1)
					(thickness 0.15)
				)
				(justify mirror)
			)
		)
		(property "Voltage" "50V"
			(at 272.65 12.07 0)
			(layer "B.Fab")
			(hide yes)
			(effects
				(font
					(size 1 1)
					(thickness 0.15)
				)
				(justify mirror)
			)
		)
		(sheetname "KR to SFI #2")
		(sheetfile "kr_sfi.kicad_sch")
		(attr smd)
		(fp_rect
			(start -0.925 0.47)
			(end 0.925 -0.47)
			(stroke
				(width 0.05)
				(type default)
			)
			(fill no)
			(layer "B.CrtYd")
		)
		(fp_line
			(start 0.504 -0.248)
			(end 0.504 0.25)
			(stroke
				(width 0.15)
				(type solid)
			)
			(layer "B.Fab")
		)
		(fp_line
			(start -0.494 -0.248)
			(end 0.504 -0.248)
			(stroke
				(width 0.15)
				(type solid)
			)
			(layer "B.Fab")
		)
		(fp_line
			(start 0.504 0.25)
			(end -0.494 0.25)
			(stroke
				(width 0.15)
				(type solid)
			)
			(layer "B.Fab")
		)
		(fp_line
			(start -0.494 0.25)
			(end -0.494 -0.248)
			(stroke
				(width 0.15)
				(type solid)
			)
			(layer "B.Fab")
		)
		(pad "1" smd roundrect
			(at -0.48 0 90)
			(size 0.59 0.64)
			(layers "B.Cu" "B.Mask" "B.Paste")
			(roundrect_rratio 0.25)
			(net 1 "GND")
			(pintype "passive")
			(teardrops
				(best_length_ratio 0.2)
				(max_length 1)
				(best_width_ratio 0.9)
				(max_width 2)
				(curved_edges yes)
				(filter_ratio 0.9)
				(enabled yes)
				(allow_two_segments yes)
				(prefer_zone_connections yes)
			)
		)
		(pad "2" smd roundrect
			(at 0.48 0 90)
			(size 0.59 0.64)
			(layers "B.Cu" "B.Mask" "B.Paste")
			(roundrect_rratio 0.25)
			(net 78 "+1V8")
			(pintype "passive")
			(teardrops
				(best_length_ratio 0.2)
				(max_length 1)
				(best_width_ratio 0.9)
				(max_width 2)
				(curved_edges yes)
				(filter_ratio 0.9)
				(enabled yes)
				(allow_two_segments yes)
				(prefer_zone_connections yes)
			)
		)
	)
	(footprint "antmicro-footprints:R_0402_1005Metric"
		(layer "B.Cu")
		(at 100.1 84.46 180)
		(descr "Resistor SMD 0402")
		(tags "resistor SMD 0402")
		(property "Reference" "R68"
			(at -1.1 0.45 0)
			(layer "B.SilkS")
			(effects
				(font
					(size 0.7 0.7)
					(thickness 0.15)
				)
				(justify left bottom mirror)
			)
		)
		(property "Value" "R_5k1_0402"
			(at -1.011843 -1.772047 0)
			(layer "B.Fab")
			(effects
				(font
					(size 0.7 0.7)
					(thickness 0.15)
				)
				(justify left bottom mirror)
			)
		)
		(property "Datasheet" "https://www.bourns.com/docs/product-datasheets/cr.pdf"
			(at 0 0 180)
			(layer "F.Fab")
			(hide yes)
			(effects
				(font
					(size 1.27 1.27)
					(thickness 0.15)
				)
			)
		)
		(property "Author" "Antmicro"
			(at 200 168.92 0)
			(layer "B.Fab")
			(hide yes)
			(effects
				(font
					(size 1 1)
					(thickness 0.15)
				)
				(justify mirror)
			)
		)
		(property "License" "Apache-2.0"
			(at 200 168.92 0)
			(layer "B.Fab")
			(hide yes)
			(effects
				(font
					(size 1 1)
					(thickness 0.15)
				)
				(justify mirror)
			)
		)
		(property "MPN" "CR0402-FX-5101GLF"
			(at 200 168.92 0)
			(layer "B.Fab")
			(hide yes)
			(effects
				(font
					(size 1 1)
					(thickness 0.15)
				)
				(justify mirror)
			)
		)
		(property "Manufacturer" "Bourns"
			(at 200 168.92 0)
			(layer "B.Fab")
			(hide yes)
			(effects
				(font
					(size 1 1)
					(thickness 0.15)
				)
				(justify mirror)
			)
		)
		(property "Public" "False"
			(at 200 168.92 0)
			(layer "B.Fab")
			(hide yes)
			(effects
				(font
					(size 1 1)
					(thickness 0.15)
				)
				(justify mirror)
			)
		)
		(property "Tolerance" "1%"
			(at 200 168.92 0)
			(layer "B.Fab")
			(hide yes)
			(effects
				(font
					(size 1 1)
					(thickness 0.15)
				)
				(justify mirror)
			)
		)
		(property "Val" "5k1"
			(at 200 168.92 0)
			(layer "B.Fab")
			(hide yes)
			(effects
				(font
					(size 1 1)
					(thickness 0.15)
				)
				(justify mirror)
			)
		)
		(sheetname "USB-C console")
		(sheetfile "usb-c_console.kicad_sch")
		(attr smd)
		(fp_rect
			(start -0.925 0.47)
			(end 0.925 -0.47)
			(stroke
				(width 0.05)
				(type default)
			)
			(fill no)
			(layer "B.CrtYd")
		)
		(fp_rect
			(start -0.5 0.25)
			(end 0.5 -0.25)
			(stroke
				(width 0.15)
				(type solid)
			)
			(fill no)
			(layer "B.Fab")
		)
		(pad "1" smd roundrect
			(at -0.48 0 180)
			(size 0.59 0.64)
			(layers "B.Cu" "B.Mask" "B.Paste")
			(roundrect_rratio 0.25)
			(net 182 "Net-(J3-CC_{2})")
			(pintype "passive")
			(teardrops
				(best_length_ratio 0.2)
				(max_length 1)
				(best_width_ratio 0.9)
				(max_width 2)
				(curved_edges yes)
				(filter_ratio 0.9)
				(enabled yes)
				(allow_two_segments yes)
				(prefer_zone_connections yes)
			)
		)
		(pad "2" smd roundrect
			(at 0.48 0 180)
			(size 0.59 0.64)
			(layers "B.Cu" "B.Mask" "B.Paste")
			(roundrect_rratio 0.25)
			(net 1 "GND")
			(pintype "passive")
			(teardrops
				(best_length_ratio 0.2)
				(max_length 1)
				(best_width_ratio 0.9)
				(max_width 2)
				(curved_edges yes)
				(filter_ratio 0.9)
				(enabled yes)
				(allow_two_segments yes)
				(prefer_zone_connections yes)
			)
		)
	)
	(footprint "antmicro-footprints:C_0402_1005Metric"
		(layer "B.Cu")
		(at 197.853588 137.730545 135)
		(descr "Capacitor SMD 0402")
		(tags "capacitor SMD 0402")
		(property "Reference" "C132"
			(at -2.768935 -0.026347 135)
			(layer "B.SilkS")
			(effects
				(font
					(size 0.7 0.7)
					(thickness 0.15)
				)
				(justify right bottom mirror)
			)
		)
		(property "Value" "C_220n_0402"
			(at -1.022927 -2.155213 135)
			(layer "B.Fab")
			(effects
				(font
					(size 0.7 0.7)
					(thickness 0.15)
				)
				(justify right bottom mirror)
			)
		)
		(property "Datasheet" "https://www.yageo.com/en/Chart/Download/pdf/CC0402KRX5R6BB224"
			(at 0 0 135)
			(layer "F.Fab")
			(hide yes)
			(effects
				(font
					(size 1.27 1.27)
					(thickness 0.15)
				)
			)
		)
		(property "Author" "Antmicro"
			(at 337.710001 -37.09 45)
			(layer "B.Fab")
			(hide yes)
			(effects
				(font
					(size 1 1)
					(thickness 0.15)
				)
				(justify mirror)
			)
		)
		(property "Dielectric" ""
			(at 337.710001 -37.09 45)
			(layer "B.Fab")
			(hide yes)
			(effects
				(font
					(size 1 1)
					(thickness 0.15)
				)
				(justify mirror)
			)
		)
		(property "License" "Apache-2.0"
			(at 337.710001 -37.09 45)
			(layer "B.Fab")
			(hide yes)
			(effects
				(font
					(size 1 1)
					(thickness 0.15)
				)
				(justify mirror)
			)
		)
		(property "MPN" "CC0402KRX5R6BB224"
			(at 337.710001 -37.09 45)
			(layer "B.Fab")
			(hide yes)
			(effects
				(font
					(size 1 1)
					(thickness 0.15)
				)
				(justify mirror)
			)
		)
		(property "Manufacturer" "YAGEO"
			(at 337.710001 -37.09 45)
			(layer "B.Fab")
			(hide yes)
			(effects
				(font
					(size 1 1)
					(thickness 0.15)
				)
				(justify mirror)
			)
		)
		(property "Public" "False"
			(at 337.710001 -37.09 45)
			(layer "B.Fab")
			(hide yes)
			(effects
				(font
					(size 1 1)
					(thickness 0.15)
				)
				(justify mirror)
			)
		)
		(property "Val" "220n"
			(at 337.710001 -37.09 45)
			(layer "B.Fab")
			(hide yes)
			(effects
				(font
					(size 1 1)
					(thickness 0.15)
				)
				(justify mirror)
			)
		)
		(property "Voltage" ""
			(at 337.710001 -37.09 45)
			(layer "B.Fab")
			(hide yes)
			(effects
				(font
					(size 1 1)
					(thickness 0.15)
				)
				(justify mirror)
			)
		)
		(sheetname "PCIe redriver")
		(sheetfile "pcie_redriver.kicad_sch")
		(attr smd)
		(fp_poly
			(pts
				(xy -0.925 0.47) (xy 0.925 0.47) (xy 0.925 -0.47) (xy -0.925 -0.47)
			)
			(stroke
				(width 0.05)
				(type default)
			)
			(fill no)
			(layer "B.CrtYd")
		)
		(fp_line
			(start 0.504 -0.248)
			(end 0.504 0.25)
			(stroke
				(width 0.15)
				(type solid)
			)
			(layer "B.Fab")
		)
		(fp_line
			(start 0.504 0.25)
			(end -0.494 0.25)
			(stroke
				(width 0.15)
				(type solid)
			)
			(layer "B.Fab")
		)
		(fp_line
			(start -0.494 -0.248)
			(end 0.504 -0.248)
			(stroke
				(width 0.15)
				(type solid)
			)
			(layer "B.Fab")
		)
		(fp_line
			(start -0.494 0.25)
			(end -0.494 -0.248)
			(stroke
				(width 0.15)
				(type solid)
			)
			(layer "B.Fab")
		)
		(pad "1" smd roundrect
			(at -0.48 0 135)
			(size 0.59 0.64)
			(layers "B.Cu" "B.Mask" "B.Paste")
			(roundrect_rratio 0.25)
			(net 222 "/Com Express 7 Interfaces/PCIe_{B1x4}.RX0+")
			(pintype "passive")
			(teardrops
				(best_length_ratio 0.2)
				(max_length 1)
				(best_width_ratio 0.9)
				(max_width 2)
				(curved_edges yes)
				(filter_ratio 0.9)
				(enabled yes)
				(allow_two_segments yes)
				(prefer_zone_connections yes)
			)
		)
		(pad "2" smd roundrect
			(at 0.48 0 135)
			(size 0.59 0.64)
			(layers "B.Cu" "B.Mask" "B.Paste")
			(roundrect_rratio 0.25)
			(net 957 "/PCIe redriver/PCIe_{I}_C.RX0+")
			(pintype "passive")
			(teardrops
				(best_length_ratio 0.2)
				(max_length 1)
				(best_width_ratio 0.9)
				(max_width 2)
				(curved_edges yes)
				(filter_ratio 0.9)
				(enabled yes)
				(allow_two_segments yes)
				(prefer_zone_connections yes)
			)
		)
	)
	(footprint "antmicro-footprints:R_0402_1005Metric"
		(layer "B.Cu")
		(at 121.25 150.81 90)
		(descr "Resistor SMD 0402")
		(tags "resistor SMD 0402")
		(property "Reference" "R216"
			(at -3.6 0.45 90)
			(layer "B.SilkS")
			(effects
				(font
					(size 0.7 0.7)
					(thickness 0.15)
				)
				(justify right bottom mirror)
			)
		)
		(property "Value" "R_0R_0402"
			(at -1.011843 -1.772047 90)
			(layer "B.Fab")
			(effects
				(font
					(size 0.7 0.7)
					(thickness 0.15)
				)
				(justify right bottom mirror)
			)
		)
		(property "Datasheet" "https://industrial.panasonic.com/cdbs/www-data/pdf/RDA0000/AOA0000C301.pdf"
			(at 0 0 90)
			(layer "F.Fab")
			(hide yes)
			(effects
				(font
					(size 1.27 1.27)
					(thickness 0.15)
				)
			)
		)
		(property "Author" "Antmicro"
			(at 272.06 29.56 0)
			(layer "B.Fab")
			(hide yes)
			(effects
				(font
					(size 1 1)
					(thickness 0.15)
				)
				(justify mirror)
			)
		)
		(property "Current" "1A"
			(at 272.06 29.56 0)
			(layer "B.Fab")
			(hide yes)
			(effects
				(font
					(size 1 1)
					(thickness 0.15)
				)
				(justify mirror)
			)
		)
		(property "License" "Apache-2.0"
			(at 272.06 29.56 0)
			(layer "B.Fab")
			(hide yes)
			(effects
				(font
					(size 1 1)
					(thickness 0.15)
				)
				(justify mirror)
			)
		)
		(property "MPN" "ERJ2GE0R00X"
			(at 272.06 29.56 0)
			(layer "B.Fab")
			(hide yes)
			(effects
				(font
					(size 1 1)
					(thickness 0.15)
				)
				(justify mirror)
			)
		)
		(property "Manufacturer" "Panasonic"
			(at 272.06 29.56 0)
			(layer "B.Fab")
			(hide yes)
			(effects
				(font
					(size 1 1)
					(thickness 0.15)
				)
				(justify mirror)
			)
		)
		(property "Public" "False"
			(at 272.06 29.56 0)
			(layer "B.Fab")
			(hide yes)
			(effects
				(font
					(size 1 1)
					(thickness 0.15)
				)
				(justify mirror)
			)
		)
		(property "Tolerance" ""
			(at 272.06 29.56 0)
			(layer "B.Fab")
			(hide yes)
			(effects
				(font
					(size 1 1)
					(thickness 0.15)
				)
				(justify mirror)
			)
		)
		(property "Val" "0R"
			(at 272.06 29.56 0)
			(layer "B.Fab")
			(hide yes)
			(effects
				(font
					(size 1 1)
					(thickness 0.15)
				)
				(justify mirror)
			)
		)
		(sheetname "PCIe redriver")
		(sheetfile "pcie_redriver.kicad_sch")
		(attr smd)
		(fp_rect
			(start -0.925 0.47)
			(end 0.925 -0.47)
			(stroke
				(width 0.05)
				(type default)
			)
			(fill no)
			(layer "B.CrtYd")
		)
		(fp_rect
			(start -0.5 0.25)
			(end 0.5 -0.25)
			(stroke
				(width 0.15)
				(type solid)
			)
			(fill no)
			(layer "B.Fab")
		)
		(pad "1" smd roundrect
			(at -0.48 0 90)
			(size 0.59 0.64)
			(layers "B.Cu" "B.Mask" "B.Paste")
			(roundrect_rratio 0.25)
			(net 2 "+3V3")
			(pintype "passive")
			(teardrops
				(best_length_ratio 0.2)
				(max_length 1)
				(best_width_ratio 0.9)
				(max_width 2)
				(curved_edges yes)
				(filter_ratio 0.9)
				(enabled yes)
				(allow_two_segments yes)
				(prefer_zone_connections yes)
			)
		)
		(pad "2" smd roundrect
			(at 0.48 0 90)
			(size 0.59 0.64)
			(layers "B.Cu" "B.Mask" "B.Paste")
			(roundrect_rratio 0.25)
			(net 631 "Net-(U39-RXDET)")
			(pintype "passive")
			(teardrops
				(best_length_ratio 0.2)
				(max_length 1)
				(best_width_ratio 0.9)
				(max_width 2)
				(curved_edges yes)
				(filter_ratio 0.9)
				(enabled yes)
				(allow_two_segments yes)
				(prefer_zone_connections yes)
			)
		)
	)
)
